# TIMECARD (Time Appliance Project (Time Card)) — schematic netlist excerpt (pin names and nets, part order shuffled) for the footprints in the layout excerpt that follows; sources: Cadence DE-HDL packaged netlist, KiCad conversion of R4006-B0001-02_R01.brd

R5  RESISTOR  10KOHM 1%  pkg SMC_0402R_H016  page 27 : \1\ = XP12R0V_A_EN ; \2\ = SG
R166  RESISTOR  1.13KOHM 1%  pkg SMC_0402R  page 30 : \1\ = XP1R8V_VIN ; \2\ = XP1R8V_EN_R

(kicad_pcb
	(version 20260206)
	(generator "pcbnew")
	(generator_version "10.0")
	(general
		(thickness 1.6)
		(legacy_teardrops no)
	)
	(paper "A4")
	(title_block
		(title "timecard-production-celestica-r4006 — R4006-B0001-02_R01.brd")
		(comment 1 "Time Appliance Project (Time Card) / footprints 574-575 of 1113")
	)
	(layers
		(0 "F.Cu" signal "TOP")
		(4 "In1.Cu" signal "L02_GND1")
		(6 "In2.Cu" signal "L03_SIG1")
		(8 "In3.Cu" signal "L04_GND2")
		(10 "In4.Cu" signal "L05_VCC1")
		(12 "In5.Cu" signal "L06_VCC2")
		(14 "In6.Cu" signal "L07_GND3")
		(16 "In7.Cu" signal "L08_SIG2")
		(18 "In8.Cu" signal "L09_GND4")
		(2 "B.Cu" signal "BOTTOM")
		(9 "F.Adhes" user "F.Adhesive")
		(11 "B.Adhes" user "B.Adhesive")
		(13 "F.Paste" user "Package Geometry/Pastemask Top")
		(15 "B.Paste" user "Package Geometry/Pastemask Bottom")
		(5 "F.SilkS" user "Ref Des/Silkscreen Top")
		(7 "B.SilkS" user "Ref Des/Silkscreen Bottom")
		(1 "F.Mask" user "Board Geometry/Soldermask Top")
		(3 "B.Mask" user "Board Geometry/Soldermask Bottom")
		(17 "Dwgs.User" user "User.Drawings")
		(19 "Cmts.User" user "User.Comments")
		(21 "Eco1.User" user "User.Eco1")
		(23 "Eco2.User" user "User.Eco2")
		(25 "Edge.Cuts" user "Board Geometry/Outline")
		(27 "Margin" user)
		(31 "F.CrtYd" user "Package Geometry/Place Bound Top")
		(29 "B.CrtYd" user "Package Geometry/Place Bound Bottom")
		(35 "F.Fab" user "Ref Des/Assembly Top")
		(33 "B.Fab" user "Ref Des/Assembly Bottom")
	)
	(footprint ""
		(layer "F.Cu")
		(at 145.8214 -89.3318)
		(property "Reference" "R5"
			(at -0.2794 7.96417 0)
			(unlocked yes)
			(layer "F.SilkS")
			(effects
				(font
					(size 0.7874 0.5842)
					(thickness 0.1524)
				)
			)
		)
		(property "Value" "VAL*"
			(at 0.02032 2.13233 0)
			(unlocked yes)
			(layer "F.Fab")
			(hide yes)
			(effects
				(font
					(size 0.7874 0.5842)
					(thickness 0.1524)
				)
			)
		)
		(property "Device Type" "RESISTOR-G155-11002-01,10KOHM,A"
			(at 0.008382 1.210564 0)
			(unlocked yes)
			(layer "F.Fab")
			(hide yes)
			(effects
				(font
					(size 0.7874 0.5842)
					(thickness 0.1524)
				)
			)
		)
		(property "User Part Number" "PARTNUM*"
			(at 0.02032 4.024884 0)
			(unlocked yes)
			(layer "Cmts.User")
			(hide yes)
			(effects
				(font
					(size 0.7874 0.5842)
					(thickness 0.1524)
				)
			)
		)
		(property "Tolerance" "TOL*"
			(at 0.044704 3.05435 0)
			(unlocked yes)
			(layer "Cmts.User")
			(hide yes)
			(effects
				(font
					(size 0.7874 0.5842)
					(thickness 0.1524)
				)
			)
		)
		(duplicate_pad_numbers_are_jumpers no)
		(fp_line
			(start -1.143 -0.5588)
			(end -1.143 0.5588)
			(stroke
				(width 0.1)
				(type default)
			)
			(layer "F.SilkS")
		)
		(fp_line
			(start -1.143 0.5588)
			(end 1.143 0.5588)
			(stroke
				(width 0.1)
				(type default)
			)
			(layer "F.SilkS")
		)
		(fp_line
			(start 1.143 -0.5588)
			(end -1.143 -0.5588)
			(stroke
				(width 0.1)
				(type default)
			)
			(layer "F.SilkS")
		)
		(fp_line
			(start 1.143 0.5588)
			(end 1.143 -0.5588)
			(stroke
				(width 0.1)
				(type default)
			)
			(layer "F.SilkS")
		)
		(fp_rect
			(start -1.143 -0.5588)
			(end 1.143 0.5588)
			(stroke
				(width 0)
				(type default)
			)
			(fill no)
			(layer "F.CrtYd")
		)
		(fp_line
			(start -0.508 -0.3048)
			(end -0.508 0.3048)
			(stroke
				(width 0.1)
				(type default)
			)
			(layer "F.Fab")
		)
		(fp_line
			(start -0.508 0.3048)
			(end 0.508 0.3048)
			(stroke
				(width 0.1)
				(type default)
			)
			(layer "F.Fab")
		)
		(fp_line
			(start 0.508 -0.3048)
			(end -0.508 -0.3048)
			(stroke
				(width 0.1)
				(type default)
			)
			(layer "F.Fab")
		)
		(fp_line
			(start 0.508 0.3048)
			(end 0.508 -0.3048)
			(stroke
				(width 0.1)
				(type default)
			)
			(layer "F.Fab")
		)
		(pad "1" smd rect
			(at -0.5334 0)
			(size 0.7112 0.6096)
			(layers "F.Cu" "F.Mask" "F.Paste")
			(net "XP12R0V_A_EN")
		)
		(pad "2" smd rect
			(at 0.5334 0)
			(size 0.7112 0.6096)
			(layers "F.Cu" "F.Mask" "F.Paste")
			(net "SG")
		)
		(zone
			(layer "F.Cu")
			(hatch none 0.5)
			(connect_pads
				(clearance 0)
			)
			(min_thickness 0.25)
			(keepout
				(tracks allowed)
				(vias not_allowed)
				(pads allowed)
				(copperpour not_allowed)
				(footprints allowed)
			)
			(placement
				(enabled no)
				(sheetname "")
			)
			(fill
				(thermal_gap 0.5)
				(thermal_bridge_width 0.5)
				(island_removal_mode 0)
			)
			(polygon
				(pts
					(xy 145.7452 -89.6366) (xy 145.7452 -89.027) (xy 145.8976 -89.027) (xy 145.8976 -89.6366)
				)
			)
		)
	)
	(footprint ""
		(layer "F.Cu")
		(at 125.984 -66.421 90)
		(property "Reference" "R166"
			(at 5.42163 0.127 0)
			(unlocked yes)
			(layer "F.SilkS")
			(effects
				(font
					(size 0.7874 0.5842)
					(thickness 0.1524)
				)
			)
		)
		(property "Value" "VAL*"
			(at 0.0508 2.245106 90)
			(unlocked yes)
			(layer "F.Fab")
			(hide yes)
			(effects
				(font
					(size 0.7874 0.5842)
					(thickness 0.1524)
				)
			)
		)
		(property "Tolerance" "TOL*"
			(at 0.0508 3.261106 90)
			(unlocked yes)
			(layer "Cmts.User")
			(hide yes)
			(effects
				(font
					(size 0.7874 0.5842)
					(thickness 0.1524)
				)
			)
		)
		(property "Device Type" "RESISTOR-G152-00055-01,1.13KOHA"
			(at 0.0762 1.254506 90)
			(unlocked yes)
			(layer "F.Fab")
			(hide yes)
			(effects
				(font
					(size 0.7874 0.5842)
					(thickness 0.1524)
				)
			)
		)
		(property "User Part Number" "PARTNUM*"
			(at 0.0762 4.302506 90)
			(unlocked yes)
			(layer "Cmts.User")
			(hide yes)
			(effects
				(font
					(size 0.7874 0.5842)
					(thickness 0.1524)
				)
			)
		)
		(duplicate_pad_numbers_are_jumpers no)
		(fp_line
			(start 1.143 -0.5588)
			(end -1.143 -0.5588)
			(stroke
				(width 0.1)
				(type default)
			)
			(layer "F.SilkS")
		)
		(fp_line
			(start -1.143 -0.5588)
			(end -1.143 0.5588)
			(stroke
				(width 0.1)
				(type default)
			)
			(layer "F.SilkS")
		)
		(fp_line
			(start 1.143 0.5588)
			(end 1.143 -0.5588)
			(stroke
				(width 0.1)
				(type default)
			)
			(layer "F.SilkS")
		)
		(fp_line
			(start -1.143 0.5588)
			(end 1.143 0.5588)
			(stroke
				(width 0.1)
				(type default)
			)
			(layer "F.SilkS")
		)
		(fp_rect
			(start 1.143 -0.5588)
			(end -1.143 0.5588)
			(stroke
				(width 0)
				(type default)
			)
			(fill no)
			(layer "F.CrtYd")
		)
		(fp_line
			(start 0.508 -0.3048)
			(end -0.508 -0.3048)
			(stroke
				(width 0.1)
				(type default)
			)
			(layer "F.Fab")
		)
		(fp_line
			(start -0.508 -0.3048)
			(end -0.508 0.3048)
			(stroke
				(width 0.1)
				(type default)
			)
			(layer "F.Fab")
		)
		(fp_line
			(start 0.508 0.3048)
			(end 0.508 -0.3048)
			(stroke
				(width 0.1)
				(type default)
			)
			(layer "F.Fab")
		)
		(fp_line
			(start -0.508 0.3048)
			(end 0.508 0.3048)
			(stroke
				(width 0.1)
				(type default)
			)
			(layer "F.Fab")
		)
		(pad "1" smd rect
			(at -0.5334 0 90)
			(size 0.7112 0.6096)
			(layers "F.Cu" "F.Mask" "F.Paste")
			(net "XP1R8V_VIN")
		)
		(pad "2" smd rect
			(at 0.5334 0 90)
			(size 0.7112 0.6096)
			(layers "F.Cu" "F.Mask" "F.Paste")
			(net "XP1R8V_EN_R")
		)
		(zone
			(layer "F.Cu")
			(hatch none 0.5)
			(connect_pads
				(clearance 0)
			)
			(min_thickness 0.25)
			(keepout
				(tracks allowed)
				(vias not_allowed)
				(pads allowed)
				(copperpour not_allowed)
				(footprints allowed)
			)
			(placement
				(enabled no)
				(sheetname "")
			)
			(fill
				(thermal_gap 0.5)
				(thermal_bridge_width 0.5)
				(island_removal_mode 0)
			)
			(polygon
				(pts
					(xy 125.6792 -66.4972) (xy 125.6792 -66.3448) (xy 126.2888 -66.3448) (xy 126.2888 -66.4972)
				)
			)
		)
	)
)
